# BASEBOARD_FAB2 (Tioga Pass) — schematic netlist excerpt (pin names and nets, part order shuffled) for the footprints in the layout excerpt that follows; sources: Cadence DE-HDL packaged netlist, KiCad conversion of Wiwynn_Tioga_Pass_MB.brd

C2N25  CAP_A  1.0UF 6.3V 10% X6S  pkg 0402V  page 130 : A = P3V3_STBY ; B = GND
C4L5  CAPP  470UF 2.5V 20% ALUM  pkg 3018  page 220 : A = PVDDQ_DEF ; B = GND

(kicad_pcb
	(version 20260206)
	(generator "pcbnew")
	(generator_version "10.0")
	(general
		(thickness 1.6)
		(legacy_teardrops no)
	)
	(paper "A4")
	(title_block
		(title "Wiwynn_Tioga_Pass_MB.brd")
		(comment 1 "Tioga Pass / footprints 4643-4644 of 4770")
	)
	(layers
		(0 "F.Cu" signal "TOP")
		(4 "In1.Cu" signal "L2GND")
		(6 "In2.Cu" signal "L3")
		(8 "In3.Cu" signal "L4GND")
		(10 "In4.Cu" signal "L5")
		(12 "In5.Cu" signal "L6GND")
		(14 "In6.Cu" signal "L7VCC")
		(16 "In7.Cu" signal "L8VCC")
		(18 "In8.Cu" signal "L9GND")
		(20 "In9.Cu" signal "L10")
		(22 "In10.Cu" signal "L11GND")
		(24 "In11.Cu" signal "L12")
		(26 "In12.Cu" signal "L13GND")
		(2 "B.Cu" signal "BOTTOM")
		(9 "F.Adhes" user "F.Adhesive")
		(11 "B.Adhes" user "B.Adhesive")
		(13 "F.Paste" user "Package Geometry/Pastemask Top")
		(15 "B.Paste" user "Package Geometry/Pastemask Bottom")
		(5 "F.SilkS" user "Ref Des/Silkscreen Top")
		(7 "B.SilkS" user "Ref Des/Silkscreen Bottom")
		(1 "F.Mask" user "Board Geometry/Soldermask Top")
		(3 "B.Mask" user "Board Geometry/Soldermask Bottom")
		(17 "Dwgs.User" user "User.Drawings")
		(19 "Cmts.User" user "User.Comments")
		(21 "Eco1.User" user "User.Eco1")
		(23 "Eco2.User" user "User.Eco2")
		(25 "Edge.Cuts" user "Board Geometry/Outline")
		(27 "Margin" user)
		(31 "F.CrtYd" user "Package Geometry/Place Bound Top")
		(29 "B.CrtYd" user "Package Geometry/Place Bound Bottom")
		(35 "F.Fab" user "Ref Des/Assembly Top")
		(33 "B.Fab" user "Ref Des/Assembly Bottom")
	)
	(footprint ""
		(layer "B.Cu")
		(at 391.8839 -103.3272 90)
		(property "Reference" "C2N25"
			(at 0 0 90)
			(layer "B.SilkS")
			(hide yes)
			(effects
				(font
					(size 1.27 1.27)
				)
				(justify mirror)
			)
		)
		(property "Value" ""
			(at 0 0 90)
			(layer "B.Fab")
			(effects
				(font
					(size 1.27 1.27)
				)
				(justify mirror)
			)
		)
		(duplicate_pad_numbers_are_jumpers no)
		(fp_rect
			(start 0.2794 0.9144)
			(end -0.2794 -0.1143)
			(stroke
				(width 0)
				(type default)
			)
			(fill no)
			(layer "B.CrtYd")
		)
		(fp_line
			(start 0.2794 -0.1143)
			(end -0.2794 -0.1143)
			(stroke
				(width 0.1)
				(type default)
			)
			(layer "B.Fab")
		)
		(fp_line
			(start -0.2794 -0.1143)
			(end -0.2794 0.9144)
			(stroke
				(width 0.1)
				(type default)
			)
			(layer "B.Fab")
		)
		(fp_line
			(start 0.2794 0.9144)
			(end 0.2794 -0.1143)
			(stroke
				(width 0.1)
				(type default)
			)
			(layer "B.Fab")
		)
		(fp_line
			(start -0.2794 0.9144)
			(end 0.2794 0.9144)
			(stroke
				(width 0.1)
				(type default)
			)
			(layer "B.Fab")
		)
		(pad "1" smd custom
			(at 0 0)
			(size 0.10414 0.10414)
			(layers "B.Cu" "B.Mask" "B.Paste")
			(net "P3V3_STBY")
			(options
				(clearance outline)
				(anchor circle)
			)
			(primitives
				(gr_poly
					(pts
						(xy -0.20828 -0.08636) (xy -0.20828 0.08636) (xy -0.08636 0.20828) (xy 0.086614 0.20828) (xy 0.20828 0.086614)
						(xy 0.20828 -0.08636) (xy 0.08636 -0.20828) (xy -0.08636 -0.20828)
					)
					(width 0)
					(fill yes)
				)
			)
		)
		(pad "2" smd custom
			(at 0 0.8001)
			(size 0.10414 0.10414)
			(layers "B.Cu" "B.Mask" "B.Paste")
			(net "GND")
			(options
				(clearance outline)
				(anchor circle)
			)
			(primitives
				(gr_poly
					(pts
						(xy -0.20828 -0.08636) (xy -0.20828 0.08636) (xy -0.08636 0.20828) (xy 0.086614 0.20828) (xy 0.20828 0.086614)
						(xy 0.20828 -0.08636) (xy 0.08636 -0.20828) (xy -0.08636 -0.20828)
					)
					(width 0)
					(fill yes)
				)
			)
		)
		(zone
			(layer "B.Cu")
			(hatch none 0.5)
			(connect_pads
				(clearance 0)
			)
			(min_thickness 0.25)
			(keepout
				(tracks allowed)
				(vias not_allowed)
				(pads allowed)
				(copperpour not_allowed)
				(footprints allowed)
			)
			(placement
				(enabled no)
				(sheetname "")
			)
			(fill
				(thermal_gap 0.5)
				(thermal_bridge_width 0.5)
				(island_removal_mode 0)
			)
			(polygon
				(pts
					(xy 392.09345 -103.41483) (xy 392.47445 -103.41483) (xy 392.47445 -103.23957) (xy 392.09345 -103.239316)
				)
			)
		)
		(zone
			(layer "B.Cu")
			(hatch none 0.5)
			(connect_pads
				(clearance 0)
			)
			(min_thickness 0.25)
			(keepout
				(tracks not_allowed)
				(vias allowed)
				(pads allowed)
				(copperpour not_allowed)
				(footprints allowed)
			)
			(placement
				(enabled no)
				(sheetname "")
			)
			(fill
				(thermal_gap 0.5)
				(thermal_bridge_width 0.5)
				(island_removal_mode 0)
			)
			(polygon
				(pts
					(xy 392.09345 -103.41483) (xy 392.47445 -103.41483) (xy 392.47445 -103.23957) (xy 392.09345 -103.239316)
				)
			)
		)
	)
	(footprint ""
		(layer "B.Cu")
		(at 332.105 -141.351 90)
		(property "Reference" "C4L5"
			(at -3.07467 8.001 0)
			(unlocked yes)
			(layer "B.SilkS")
			(effects
				(font
					(size 0.7874 0.5842)
					(thickness 0.1524)
				)
				(justify mirror)
			)
		)
		(property "Value" ""
			(at 0 0 90)
			(layer "B.Fab")
			(effects
				(font
					(size 1.27 1.27)
				)
				(justify mirror)
			)
		)
		(duplicate_pad_numbers_are_jumpers no)
		(fp_line
			(start 2.563114 -1.616456)
			(end 2.563114 1.633728)
			(stroke
				(width 0.1524)
				(type default)
			)
			(layer "B.SilkS")
		)
		(fp_line
			(start 1.6002 -1.616456)
			(end 2.563114 -1.616456)
			(stroke
				(width 0.1524)
				(type default)
			)
			(layer "B.SilkS")
		)
		(fp_line
			(start -1.6002 -1.616456)
			(end -2.504948 -1.616456)
			(stroke
				(width 0.1524)
				(type default)
			)
			(layer "B.SilkS")
		)
		(fp_line
			(start -2.504948 -1.616456)
			(end -2.504948 1.633728)
			(stroke
				(width 0.1524)
				(type default)
			)
			(layer "B.SilkS")
		)
		(fp_line
			(start 2.563114 1.633728)
			(end 1.6002 1.633728)
			(stroke
				(width 0.1524)
				(type default)
			)
			(layer "B.SilkS")
		)
		(fp_line
			(start -2.504948 1.633728)
			(end -1.6002 1.633728)
			(stroke
				(width 0.1524)
				(type default)
			)
			(layer "B.SilkS")
		)
		(fp_line
			(start 2.286 7.366)
			(end 2.286 1.632712)
			(stroke
				(width 0.1524)
				(type default)
			)
			(layer "B.SilkS")
		)
		(fp_line
			(start 2.286 7.366)
			(end 1.60147 7.366)
			(stroke
				(width 0.1524)
				(type default)
			)
			(layer "B.SilkS")
		)
		(fp_line
			(start -2.286 7.366)
			(end -2.286 1.63195)
			(stroke
				(width 0.1524)
				(type default)
			)
			(layer "B.SilkS")
		)
		(fp_line
			(start -2.286 7.366)
			(end -1.600708 7.366)
			(stroke
				(width 0.1524)
				(type default)
			)
			(layer "B.SilkS")
		)
		(fp_rect
			(start 2.286 7.366)
			(end -2.286 -0.254)
			(stroke
				(width 0)
				(type default)
			)
			(fill no)
			(layer "B.CrtYd")
		)
		(fp_line
			(start 2.286 -0.254)
			(end -2.286 -0.254)
			(stroke
				(width 0.1)
				(type default)
			)
			(layer "B.Fab")
		)
		(fp_line
			(start -2.286 -0.254)
			(end -2.286 7.366)
			(stroke
				(width 0.1)
				(type default)
			)
			(layer "B.Fab")
		)
		(fp_line
			(start 2.286 7.366)
			(end 2.286 -0.254)
			(stroke
				(width 0.1)
				(type default)
			)
			(layer "B.Fab")
		)
		(fp_line
			(start -2.286 7.366)
			(end 2.286 7.366)
			(stroke
				(width 0.1)
				(type default)
			)
			(layer "B.Fab")
		)
		(pad "1" smd rect
			(at 0 0 270)
			(size 2.54 3.048)
			(layers "B.Cu" "B.Mask" "B.Paste")
			(net "PVDDQ_DEF")
		)
		(pad "2" smd rect
			(at 0 7.112 270)
			(size 2.54 3.048)
			(layers "B.Cu" "B.Mask" "B.Paste")
			(net "GND")
		)
	)
)
